(kicad_pcb
	(version 20240108)
	(generator "pcbnew")
	(generator_version "8.0")
	(general
		(thickness 1.62)
		(legacy_teardrops no)
	)
	(paper "A4")
	(title_block
		(title "Jetson Orin Baseboard")
		(date "2025-03-12")
		(rev "1.3.4")
		(company "Antmicro Ltd")
		(comment 1 "www.antmicro.com")
		(comment 9 "footprints 645-647 of 677")
	)
	(layers
		(0 "F.Cu" signal)
		(1 "In1.Cu" signal)
		(2 "In2.Cu" signal)
		(3 "In3.Cu" signal)
		(4 "In4.Cu" jumper)
		(5 "In5.Cu" signal)
		(6 "In6.Cu" signal)
		(31 "B.Cu" signal)
		(32 "B.Adhes" user "B.Adhesive")
		(33 "F.Adhes" user "F.Adhesive")
		(34 "B.Paste" user)
		(35 "F.Paste" user)
		(36 "B.SilkS" user "B.Silkscreen")
		(37 "F.SilkS" user "F.Silkscreen")
		(38 "B.Mask" user)
		(39 "F.Mask" user)
		(40 "Dwgs.User" user "User.Drawings")
		(41 "Cmts.User" user "User.Comments")
		(42 "Eco1.User" user "User.Eco1")
		(43 "Eco2.User" user "User.Eco2")
		(44 "Edge.Cuts" user)
		(45 "Margin" user)
		(46 "B.CrtYd" user "B.Courtyard")
		(47 "F.CrtYd" user "F.Courtyard")
		(48 "B.Fab" user)
		(49 "F.Fab" user)
	)
	(footprint "antmicro-footprints:R_0402_1005Metric"
		(layer "B.Cu")
		(at 67.7 72.9)
		(descr "Resistor SMD 0402")
		(tags "resistor SMD 0402")
		(property "Reference" "R259"
			(at 1.49 -0.58 180)
			(layer "B.SilkS")
			(effects
				(font
					(size 0.7 0.7)
					(thickness 0.15)
				)
				(justify left bottom mirror)
			)
		)
		(property "Value" "R_10k_0402"
			(at 0 -1.4 180)
			(layer "B.Fab")
			(effects
				(font
					(size 0.7 0.7)
					(thickness 0.15)
				)
				(justify left bottom mirror)
			)
		)
		(property "Footprint" "antmicro-footprints:R_0402_1005Metric"
			(at 0 0 0)
			(layer "F.Fab")
			(hide yes)
			(effects
				(font
					(size 1.27 1.27)
					(thickness 0.15)
				)
			)
		)
		(property "Datasheet" "https://www.bourns.com/docs/product-datasheets/cr.pdf"
			(at 0 0 0)
			(layer "F.Fab")
			(hide yes)
			(effects
				(font
					(size 1.27 1.27)
					(thickness 0.15)
				)
			)
		)
		(property "Author" "Antmicro"
			(at 0 0 0)
			(layer "B.Fab")
			(hide yes)
			(effects
				(font
					(size 1 1)
					(thickness 0.15)
				)
				(justify mirror)
			)
		)
		(property "License" "Apache-2.0"
			(at 0 0 0)
			(layer "B.Fab")
			(hide yes)
			(effects
				(font
					(size 1 1)
					(thickness 0.15)
				)
				(justify mirror)
			)
		)
		(property "MPN" "CR0402-FX-1002GLF"
			(at 0 0 0)
			(layer "B.Fab")
			(hide yes)
			(effects
				(font
					(size 1 1)
					(thickness 0.15)
				)
				(justify mirror)
			)
		)
		(property "Manufacturer" "Bourns"
			(at 0 0 0)
			(layer "B.Fab")
			(hide yes)
			(effects
				(font
					(size 1 1)
					(thickness 0.15)
				)
				(justify mirror)
			)
		)
		(property "Tolerance" "1%"
			(at 0 0 0)
			(layer "B.Fab")
			(hide yes)
			(effects
				(font
					(size 1 1)
					(thickness 0.15)
				)
				(justify mirror)
			)
		)
		(property "Val" "10k"
			(at 0 0 0)
			(layer "B.Fab")
			(hide yes)
			(effects
				(font
					(size 1 1)
					(thickness 0.15)
				)
				(justify mirror)
			)
		)
		(sheetname "Supply")
		(sheetfile "supply.kicad_sch")
		(attr smd)
		(fp_rect
			(start -0.925 0.47)
			(end 0.925 -0.47)
			(stroke
				(width 0.05)
				(type default)
			)
			(fill none)
			(layer "B.CrtYd")
		)
		(fp_rect
			(start -0.5 0.25)
			(end 0.5 -0.25)
			(stroke
				(width 0.15)
				(type solid)
			)
			(fill none)
			(layer "B.Fab")
		)
		(fp_text user "Author: Antmicro"
			(at -0.95 -4.169 180)
			(layer "B.Fab")
			(hide yes)
			(effects
				(font
					(size 0.7 0.7)
					(thickness 0.15)
				)
				(justify left bottom mirror)
			)
		)
		(fp_text user "License: Apache-2.0"
			(at -0.95 -5.169 180)
			(layer "B.Fab")
			(hide yes)
			(effects
				(font
					(size 0.7 0.7)
					(thickness 0.15)
				)
				(justify left bottom mirror)
			)
		)
		(fp_text user "${REFERENCE}"
			(at -0.95 -3.168 180)
			(layer "B.Fab")
			(hide yes)
			(effects
				(font
					(size 0.7 0.7)
					(thickness 0.15)
				)
				(justify left bottom mirror)
			)
		)
		(pad "1" smd roundrect
			(at -0.48 0)
			(size 0.59 0.64)
			(layers "B.Cu" "B.Paste" "B.Mask")
			(roundrect_rratio 0.25)
			(net 629 "Net-(D37-A)")
			(pintype "passive")
		)
		(pad "2" smd roundrect
			(at 0.48 0)
			(size 0.59 0.64)
			(layers "B.Cu" "B.Paste" "B.Mask")
			(roundrect_rratio 0.25)
			(net 117 "3V3_STDB")
			(pintype "passive")
		)
	)
	(footprint "antmicro-footprints:C_0402_1005Metric"
		(layer "B.Cu")
		(at 65.3 75.5)
		(descr "Capacitor SMD 0402")
		(tags "capacitor SMD 0402")
		(property "Reference" "C119"
			(at 16.86 3.45 180)
			(layer "B.SilkS")
			(effects
				(font
					(size 0.7 0.7)
					(thickness 0.15)
				)
				(justify left bottom mirror)
			)
		)
		(property "Value" "C_100n_0402"
			(at 0 -1.4 180)
			(layer "B.Fab")
			(effects
				(font
					(size 0.7 0.7)
					(thickness 0.15)
				)
				(justify left bottom mirror)
			)
		)
		(property "Footprint" "antmicro-footprints:C_0402_1005Metric"
			(at 0 0 0)
			(layer "F.Fab")
			(hide yes)
			(effects
				(font
					(size 1.27 1.27)
					(thickness 0.15)
				)
			)
		)
		(property "Datasheet" "https://www.murata.com/products/productdetail?partno=GRM155R61H104KE14%23"
			(at 0 0 0)
			(layer "F.Fab")
			(hide yes)
			(effects
				(font
					(size 1.27 1.27)
					(thickness 0.15)
				)
			)
		)
		(property "Author" "Antmicro"
			(at 0 0 0)
			(layer "B.Fab")
			(hide yes)
			(effects
				(font
					(size 1 1)
					(thickness 0.15)
				)
				(justify mirror)
			)
		)
		(property "Dielectric" "X5R"
			(at 0 0 0)
			(layer "B.Fab")
			(hide yes)
			(effects
				(font
					(size 1 1)
					(thickness 0.15)
				)
				(justify mirror)
			)
		)
		(property "License" "Apache-2.0"
			(at 0 0 0)
			(layer "B.Fab")
			(hide yes)
			(effects
				(font
					(size 1 1)
					(thickness 0.15)
				)
				(justify mirror)
			)
		)
		(property "MPN" "GRM155R61H104KE14D"
			(at 0 0 0)
			(layer "B.Fab")
			(hide yes)
			(effects
				(font
					(size 1 1)
					(thickness 0.15)
				)
				(justify mirror)
			)
		)
		(property "Manufacturer" "Murata"
			(at 0 0 0)
			(layer "B.Fab")
			(hide yes)
			(effects
				(font
					(size 1 1)
					(thickness 0.15)
				)
				(justify mirror)
			)
		)
		(property "Val" "100n"
			(at 0 0 0)
			(layer "B.Fab")
			(hide yes)
			(effects
				(font
					(size 1 1)
					(thickness 0.15)
				)
				(justify mirror)
			)
		)
		(property "Voltage" "50V"
			(at 0 0 0)
			(layer "B.Fab")
			(hide yes)
			(effects
				(font
					(size 1 1)
					(thickness 0.15)
				)
				(justify mirror)
			)
		)
		(sheetname "Supply")
		(sheetfile "supply.kicad_sch")
		(attr smd)
		(fp_rect
			(start -0.925 0.47)
			(end 0.925 -0.47)
			(stroke
				(width 0.05)
				(type default)
			)
			(fill none)
			(layer "B.CrtYd")
		)
		(fp_line
			(start -0.494 -0.248)
			(end 0.504 -0.248)
			(stroke
				(width 0.15)
				(type solid)
			)
			(layer "B.Fab")
		)
		(fp_line
			(start -0.494 0.25)
			(end -0.494 -0.248)
			(stroke
				(width 0.15)
				(type solid)
			)
			(layer "B.Fab")
		)
		(fp_line
			(start 0.504 -0.248)
			(end 0.504 0.25)
			(stroke
				(width 0.15)
				(type solid)
			)
			(layer "B.Fab")
		)
		(fp_line
			(start 0.504 0.25)
			(end -0.494 0.25)
			(stroke
				(width 0.15)
				(type solid)
			)
			(layer "B.Fab")
		)
		(fp_text user "Author: Antmicro"
			(at -0.932 -4.17 180)
			(layer "B.Fab")
			(hide yes)
			(effects
				(font
					(size 0.7 0.7)
					(thickness 0.15)
				)
				(justify left bottom mirror)
			)
		)
		(fp_text user "${REFERENCE}"
			(at -0.932 -3.168 180)
			(layer "B.Fab")
			(hide yes)
			(effects
				(font
					(size 0.7 0.7)
					(thickness 0.15)
				)
				(justify left bottom mirror)
			)
		)
		(fp_text user "License: Apache-2.0"
			(at -0.932 -5.17 180)
			(layer "B.Fab")
			(hide yes)
			(effects
				(font
					(size 0.7 0.7)
					(thickness 0.15)
				)
				(justify left bottom mirror)
			)
		)
		(pad "1" smd roundrect
			(at -0.48 0)
			(size 0.59 0.64)
			(layers "B.Cu" "B.Paste" "B.Mask")
			(roundrect_rratio 0.25)
			(net 1 "GND")
			(pintype "passive")
		)
		(pad "2" smd roundrect
			(at 0.48 0)
			(size 0.59 0.64)
			(layers "B.Cu" "B.Paste" "B.Mask")
			(roundrect_rratio 0.25)
			(net 117 "3V3_STDB")
			(pintype "passive")
		)
	)
	(footprint "antmicro-footprints:Spacer_Drill3.7mm_H2.5mm_9774025151R"
		(layer "B.Cu")
		(at 40.75 86.75 180)
		(descr "Spacer M=3 h=2.5mm fi=5.1mm")
		(property "Reference" "SP8"
			(at -1.05 3.45 0)
			(layer "B.SilkS")
			(effects
				(font
					(size 0.7 0.7)
					(thickness 0.15)
				)
				(justify left bottom mirror)
			)
		)
		(property "Value" "Spacer_Drill3.7mm_H2.5mm_9774025151R"
			(at 0 -4 0)
			(layer "B.Fab")
			(effects
				(font
					(size 0.7 0.7)
					(thickness 0.15)
				)
				(justify left bottom mirror)
			)
		)
		(property "Footprint" "antmicro-footprints:Spacer_Drill3.7mm_H2.5mm_9774025151R"
			(at 0 0 180)
			(layer "F.Fab")
			(hide yes)
			(effects
				(font
					(size 1.27 1.27)
					(thickness 0.15)
				)
			)
		)
		(property "Datasheet" "https://www.we-online.com/components/products/datasheet/9774025151R.pdf"
			(at 0 0 180)
			(layer "F.Fab")
			(hide yes)
			(effects
				(font
					(size 1.27 1.27)
					(thickness 0.15)
				)
			)
		)
		(property "Author" "Antmicro"
			(at 81.5 173.5 0)
			(layer "B.Fab")
			(hide yes)
			(effects
				(font
					(size 1 1)
					(thickness 0.15)
				)
				(justify mirror)
			)
		)
		(property "License" "Apache-2.0"
			(at 81.5 173.5 0)
			(layer "B.Fab")
			(hide yes)
			(effects
				(font
					(size 1 1)
					(thickness 0.15)
				)
				(justify mirror)
			)
		)
		(property "MPN" "9774025151R"
			(at 81.5 173.5 0)
			(layer "B.Fab")
			(hide yes)
			(effects
				(font
					(size 1 1)
					(thickness 0.15)
				)
				(justify mirror)
			)
		)
		(property "Manufacturer" "Würth Elektronik"
			(at 81.5 173.5 0)
			(layer "B.Fab")
			(hide yes)
			(effects
				(font
					(size 1 1)
					(thickness 0.15)
				)
				(justify mirror)
			)
		)
		(sheetname "M.2")
		(sheetfile "m-2.kicad_sch")
		(solder_paste_ratio -1)
		(attr smd)
		(fp_circle
			(center 0 0)
			(end 3.05 0)
			(stroke
				(width 0.05)
				(type solid)
			)
			(fill none)
			(layer "B.CrtYd")
		)
		(fp_circle
			(center 0 0)
			(end 2.6 0)
			(stroke
				(width 0.15)
				(type solid)
			)
			(fill none)
			(layer "B.Fab")
		)
		(fp_text user "Author: Antmicro"
			(at -9.6 -7.7 0)
			(layer "B.Fab")
			(hide yes)
			(effects
				(font
					(size 0.7 0.7)
					(thickness 0.15)
				)
				(justify left bottom mirror)
			)
		)
		(fp_text user "${REFERENCE}"
			(at -9.6 -6.5 0)
			(layer "B.Fab")
			(hide yes)
			(effects
				(font
					(size 0.7 0.7)
					(thickness 0.15)
				)
				(justify left bottom mirror)
			)
		)
		(fp_text user "License: Apache-2.0"
			(at -9.6 -8.9 0)
			(layer "B.Fab")
			(hide yes)
			(effects
				(font
					(size 0.7 0.7)
					(thickness 0.15)
				)
				(justify left bottom mirror)
			)
		)
		(pad "" smd custom
			(at -1.7 -1.7 90)
			(size 0.62 0.62)
			(layers "B.Paste")
			(thermal_bridge_angle 90)
			(options
				(clearance outline)
				(anchor circle)
			)
			(primitives
				(gr_arc
					(start 1.266786 0.24747)
					(mid 0.285453 -0.29439)
					(end -0.250195 -1.279127)
					(width 0.2)
				)
				(gr_arc
					(start 1.259603 0.339191)
					(mid 0.218448 -0.232561)
					(end -0.34334 -1.279127)
					(width 0.2)
				)
				(gr_arc
					(start 1.255279 0.431435)
					(mid 0.152481 -0.169693)
					(end -0.436309 -1.279127)
					(width 0.2)
				)
				(gr_arc
					(start 1.253811 0.524161)
					(mid 0.087542 -0.105784)
					(end -0.529126 -1.279127)
					(width 0.2)
				)
				(gr_arc
					(start 1.275473 0.621136)
					(mid 0.0309 -0.033527)
					(end -0.621807 -1.279127)
					(width 0.2)
				)
				(gr_arc
					(start 1.263664 0.711602)
					(mid -0.037759 0.026651)
					(end -0.71437 -1.279127)
					(width 0.2)
				)
				(gr_arc
					(start 1.253435 0.802342)
					(mid -0.105837 0.087395)
					(end -0.806826 -1.279127)
					(width 0.2)
				)
				(gr_arc
					(start 1.267475 0.897258)
					(mid -0.165236 0.156885)
					(end -0.899187 -1.279127)
					(width 0.2)
				)
				(gr_arc
					(start 1.270645 0.990112)
					(mid -0.228522 0.222449)
					(end -0.991463 -1.279127)
					(width 0.2)
				)
				(gr_arc
					(start 1.266278 1.081674)
					(mid -0.294507 0.285313)
					(end -1.083663 -1.279127)
					(width 0.2)
				)
				(gr_line
					(start 1.279127 0.250195)
					(end 1.279127 1.083663)
					(width 0.2)
				)
				(gr_line
					(start -0.250195 -1.279127)
					(end -1.083663 -1.279127)
					(width 0.2)
				)
			)
		)
		(pad "" smd custom
			(at -1.7 1.7 180)
			(size 0.62 0.62)
			(layers "B.Paste")
			(thermal_bridge_angle 90)
			(options
				(clearance outline)
				(anchor circle)
			)
			(primitives
				(gr_arc
					(start 1.266786 0.24747)
					(mid 0.285453 -0.29439)
					(end -0.250195 -1.279127)
					(width 0.2)
				)
				(gr_arc
					(start 1.259603 0.339191)
					(mid 0.218448 -0.232561)
					(end -0.34334 -1.279127)
					(width 0.2)
				)
				(gr_arc
					(start 1.255279 0.431435)
					(mid 0.152481 -0.169693)
					(end -0.436309 -1.279127)
					(width 0.2)
				)
				(gr_arc
					(start 1.253811 0.524161)
					(mid 0.087542 -0.105784)
					(end -0.529126 -1.279127)
					(width 0.2)
				)
				(gr_arc
					(start 1.275473 0.621136)
					(mid 0.0309 -0.033527)
					(end -0.621807 -1.279127)
					(width 0.2)
				)
				(gr_arc
					(start 1.263664 0.711602)
					(mid -0.037759 0.026651)
					(end -0.71437 -1.279127)
					(width 0.2)
				)
				(gr_arc
					(start 1.253435 0.802342)
					(mid -0.105837 0.087395)
					(end -0.806826 -1.279127)
					(width 0.2)
				)
				(gr_arc
					(start 1.267475 0.897258)
					(mid -0.165236 0.156885)
					(end -0.899187 -1.279127)
					(width 0.2)
				)
				(gr_arc
					(start 1.270645 0.990112)
					(mid -0.228522 0.222449)
					(end -0.991463 -1.279127)
					(width 0.2)
				)
				(gr_arc
					(start 1.266278 1.081674)
					(mid -0.294507 0.285313)
					(end -1.083663 -1.279127)
					(width 0.2)
				)
				(gr_line
					(start 1.279127 0.250195)
					(end 1.279127 1.083663)
					(width 0.2)
				)
				(gr_line
					(start -0.250195 -1.279127)
					(end -1.083663 -1.279127)
					(width 0.2)
				)
			)
		)
		(pad "" smd custom
			(at 1.7 -1.7)
			(size 0.62 0.62)
			(layers "B.Paste")
			(thermal_bridge_angle 90)
			(options
				(clearance outline)
				(anchor circle)
			)
			(primitives
				(gr_arc
					(start 1.266786 0.24747)
					(mid 0.285453 -0.29439)
					(end -0.250195 -1.279127)
					(width 0.2)
				)
				(gr_arc
					(start 1.259603 0.339191)
					(mid 0.218448 -0.232561)
					(end -0.34334 -1.279127)
					(width 0.2)
				)
				(gr_arc
					(start 1.255279 0.431435)
					(mid 0.152481 -0.169693)
					(end -0.436309 -1.279127)
					(width 0.2)
				)
				(gr_arc
					(start 1.253811 0.524161)
					(mid 0.087542 -0.105784)
					(end -0.529126 -1.279127)
					(width 0.2)
				)
				(gr_arc
					(start 1.275473 0.621136)
					(mid 0.0309 -0.033527)
					(end -0.621807 -1.279127)
					(width 0.2)
				)
				(gr_arc
					(start 1.263664 0.711602)
					(mid -0.037759 0.026651)
					(end -0.71437 -1.279127)
					(width 0.2)
				)
				(gr_arc
					(start 1.253435 0.802342)
					(mid -0.105837 0.087395)
					(end -0.806826 -1.279127)
					(width 0.2)
				)
				(gr_arc
					(start 1.267475 0.897258)
					(mid -0.165236 0.156885)
					(end -0.899187 -1.279127)
					(width 0.2)
				)
				(gr_arc
					(start 1.270645 0.990112)
					(mid -0.228522 0.222449)
					(end -0.991463 -1.279127)
					(width 0.2)
				)
				(gr_arc
					(start 1.266278 1.081674)
					(mid -0.294507 0.285313)
					(end -1.083663 -1.279127)
					(width 0.2)
				)
				(gr_line
					(start 1.279127 0.250195)
					(end 1.279127 1.083663)
					(width 0.2)
				)
				(gr_line
					(start -0.250195 -1.279127)
					(end -1.083663 -1.279127)
					(width 0.2)
				)
			)
		)
		(pad "" smd custom
			(at 1.7 1.7 270)
			(size 0.62 0.62)
			(layers "B.Paste")
			(thermal_bridge_angle 90)
			(options
				(clearance outline)
				(anchor circle)
			)
			(primitives
				(gr_arc
					(start 1.266786 0.24747)
					(mid 0.285453 -0.29439)
					(end -0.250195 -1.279127)
					(width 0.2)
				)
				(gr_arc
					(start 1.259603 0.339191)
					(mid 0.218448 -0.232561)
					(end -0.34334 -1.279127)
					(width 0.2)
				)
				(gr_arc
					(start 1.255279 0.431435)
					(mid 0.152481 -0.169693)
					(end -0.436309 -1.279127)
					(width 0.2)
				)
				(gr_arc
					(start 1.253811 0.524161)
					(mid 0.087542 -0.105784)
					(end -0.529126 -1.279127)
					(width 0.2)
				)
				(gr_arc
					(start 1.275473 0.621136)
					(mid 0.0309 -0.033527)
					(end -0.621807 -1.279127)
					(width 0.2)
				)
				(gr_arc
					(start 1.263664 0.711602)
					(mid -0.037759 0.026651)
					(end -0.71437 -1.279127)
					(width 0.2)
				)
				(gr_arc
					(start 1.253435 0.802342)
					(mid -0.105837 0.087395)
					(end -0.806826 -1.279127)
					(width 0.2)
				)
				(gr_arc
					(start 1.267475 0.897258)
					(mid -0.165236 0.156885)
					(end -0.899187 -1.279127)
					(width 0.2)
				)
				(gr_arc
					(start 1.270645 0.990112)
					(mid -0.228522 0.222449)
					(end -0.991463 -1.279127)
					(width 0.2)
				)
				(gr_arc
					(start 1.266278 1.081674)
					(mid -0.294507 0.285313)
					(end -1.083663 -1.279127)
					(width 0.2)
				)
				(gr_line
					(start 1.279127 0.250195)
					(end 1.279127 1.083663)
					(width 0.2)
				)
				(gr_line
					(start -0.250195 -1.279127)
					(end -1.083663 -1.279127)
					(width 0.2)
				)
			)
		)
		(pad "1" thru_hole circle
			(at 0 0 180)
			(size 6 6)
			(drill 3.7)
			(layers "*.Cu" "*.Mask")
			(remove_unused_layers no)
			(net 1 "GND")
			(pintype "passive")
		)
	)
)
